FILE_TYPE = CONNECTIVITY;
{Allegro Design Entry HDL 17.4-2019 S026 (4007227) 1/17/2022}
"PAGE_NUMBER" = 192;
0"NC";
1"P5V_AUX\g";
2"GND\g";
3"P3V3_AUX\g";
4"GND\g";
5"GND\g";
6"GND\g";
7"GND\g";
8"P3V3_AUX\g";
9"GND\g";
10"GND\g";
11"GND\g";
12"GND\g";
13"GND\g";
14"GND\g";
15"GND\g";
16"GND\g";
17"GND\g";
18"GND\g";
19"GND\g";
20"GND\g";
21"GND\g";
22"GND\g";
23"VSENSE_VSS_SENSE_C_P1";
24"VSENSE_PVDDCR_CPU1_P1_DP";
25"VSENSE_PVDDIO_P1_VSEN1";
26"NC_PVDDCR_CPU1_P1_PWM7";
27"PVDDCR_CPU1_P1_VCCS";
28"PVDDCR_CPU1_P1\g";
29"PVDDCR_CPU1_P1_IMON1";
30"PVDDCR_CPU1_P1_VCC";
31"SVID_PVDDCR_CPU1_P1_SVTI_R";
32"SMB_CLK_PVDDCR_CPU1_P1_R";
33"SVID_PVDDCR_CPU1_P1_SVC_R1";
34"PVDDCR_CPU1_P1_IMON6";
35"SVID_PVDDCR_CPU1_P1_SVTO_R";
36"PVDDCR_CPU1_P1_RESET_N_R";
37"NC_PVDDCR_CPU1_P1_IMON7";
38"NC_PVDDCR_CPU1_P1_IMON8";
39"PWRGD_PVDDIO_P1_R";
40"SVID_PVDDCR_CPU1_P1_SVD_R1";
41"PVDDCR_CPU1_P1_SMB_ALERT_R";
42"PVDDCR_CPU1_P1_EN_R";
43"SMB_DIO_PVDDCR_CPU1_P1_R";
44"NC_PVDDCR_CPU1_P1_PWM8";
45"VSENSE_PVDDCR_CPU1_P1_VSEN0";
46"PVDDIO_P1_PWM2";
47"PWRGD_PVDDCR_CPU1_P1_R";
48"PVDDCR_CPU1_P1_PWM6";
49"PVDDCR_CPU1_P1_VMON";
50"PVDDCR_CPU1_P1_VINSEN";
51"PVDDCR_CPU1_P1_TEMP0";
52"PVDD18_S5_P1\g";
53"VSENSE_VSS_SENSE_B_P1";
54"PVDDIO_P1_IMON2";
55"PVDDCR_CPU1_P1_PWM1";
56"PVDDIO_P1_PWM4";
57"PVDDIO_P1_IMON4";
58"PVDDIO_P1_PWM3";
59"PVDDIO_P1_IMON3";
60"PVDDCR_CPU1_P1_OCP_N_R";
61"GND\g";
62"PVDDCR_CPU1_P1_EN1_ADDR_CFG";
63"PVDDIO_P1_TEMP1";
64"PVDDIO_P1_PWM1";
65"PVDDIO_P1_IMON1";
66"PVDDCR_CPU1_P1_PWM5";
67"PVDDCR_CPU1_P1_IMON5";
68"PVDDCR_CPU1_P1_PWM4";
69"PVDDCR_CPU1_P1_IMON4";
70"PVDDCR_CPU1_P1_PWM3";
71"PVDDCR_CPU1_P1_IMON3";
72"PVDDCR_CPU1_P1_PWM2";
73"PVDDCR_CPU1_P1_IMON2";
74"SVID_PVDDCR_CPU1_P1_SVTO";
75"SVID_PVDDCR_CPU1_P1_SVD_R";
76"SVID_PVDDCR_CPU1_P1_SVC_R";
77"SMB_SCM_2_R1_SCL";
78"SVID_PVDDCR_CPU1_P1_SVTI";
79"P3V3_AUX\g";
80"P3V3_AUX\g";
81"GND\g";
82"PVDD18_S5_P1\g";
83"GND\g"VOLTAGE"0";
84"GND\g";
85"P12V_AUX\g";
86"PVDD18_S5_P1\g";
87"PVDDIO_P1\g";
88"GND\g";
89"PVDDCR_CPU1_P1_RESET_N";
90"PVDDCR_CPU1_P1_SMB_ALERT";
91"SMB_SCM_2_R1_SDA";
92"PWRGD_PVDDIO_P1";
93"PVDDIO_P1_EN_R";
94"VSENSE_PVDDIO_P1_DP";
95"PVDDCR_CPU1_P1_OCP_N";
96"PVDDIO_P1_EN_G";
97"PVDDIO_P1_EN";
98"PWRGD_PVDDCR_CPU1_P1";
99"FM_PVDDCR_CPU1_P1_EN";
%"VCC_CORE"
"1","(-3725,1925)","0","pure_quanta_power","I10";
;
HDL_POWER"P5V_AUX"
CDS_LIB"pure_quanta_power";
"A"1;
%"UNIVERSAL_GND"
"1","(1375,4250)","0","pure_quanta_power","I109";
;
CDS_LIB"pure_quanta_power"
HDL_POWER"GND";
"A"2;
%"VCC_CORE"
"1","(-3250,2225)","0","pure_quanta_power","I11";
;
HDL_POWER"P3V3_AUX"
CDS_LIB"pure_quanta_power";
"A"3;
%"UNIVERSAL_GND"
"1","(1375,3950)","0","pure_quanta_power","I110";
;
CDS_LIB"pure_quanta_power"
HDL_POWER"GND";
"A"4;
%"Q_RES"
"2","(-3300,2525)","0","pure_quanta","I12";
;
LOCATION"PR244"
$SEC"1"
CDS_SEC"1"
PACK_TYPE"0402LF"
WATTAGE"1/16W"
VALUE"9.53K"
TOLERANCE"1%"
MATERIAL"CHIP"
CDS_LIB"pure_quanta"
PART_NUMBER"CS29532FB06";
"A"
$PN"1"62;
"B"
$PN"2"88;
%"Q_RES"
"1","(1300,7225)","0","pure_quanta","I124";
;
LOCATION"PR253"
$SEC"1"
CDS_SEC"1"
WATTAGE"1/16W"
MATERIAL"CHIP"
TOLERANCE"1%"
VALUE"1"
PACK_TYPE"0402LF"
CDS_LIB"pure_quanta"
PART_NUMBER"CS-1002FB04";
"B"
$PN"2"79;
"A"
$PN"1"30;
%"VCC_CORE"
"1","(1825,7350)","0","pure_quanta_power","I125";
;
HDL_POWER"P3V3_AUX"
CDS_LIB"pure_quanta_power";
"A"79;
%"Q_RES"
"1","(925,4025)","0","pure_quanta","I127";
;
LOCATION"PR12"
$SEC"1"
CDS_SEC"1"
PACK_TYPE"0402LF"
TOLERANCE"5%"
VALUE"0"
WATTAGE"1/16W"
MATERIAL"CHIP"
CDS_LIB"pure_quanta"
PART_NUMBER"CS00002JB13";
"B"
$PN"2"4;
"A"
$PN"1"38;
%"RAA229620GNPHA0"
"1","(-475,4475)","0","pure_quanta","I128";
;
LOCATION"PU34"
SEC"1"
PART_TYPE"SMLF"
MATERIAL"IC"
VALUE"RAA229620GNP#HA0"
SEC_TYPE""
NEEDS_NO_SIZE"TRUE"
CDS_LMAN_SYM_OUTLINE"-550,2850,500,-2850"
CDS_LIB"pure_quanta"
PART_NUMBER"ARF0TGP4002";
"CS10"
$PN"28"73;
"PWM10"
$PN"11"72;
"CS9"
$PN"29"71;
"PWM9"
$PN"10"70;
"CS8"
$PN"30"69;
"PWM8"
$PN"9"68;
"CS7"
$PN"31"67;
"PWM7"
$PN"8"66;
"CS0"
$PN"38"65;
"PWM0"
$PN"1"64;
"TEMP1"
$PN"43"63;
"EN1||ADDR_CFG"
$PN"42"62;
"TH_GND"
$PN"TH"61;
"OCP_L \B"
$PN"41"60;
"CS2"
$PN"36"59;
"PWM2"
$PN"3"58;
"CS3"
$PN"35"57;
"PWM3"
$PN"4"56;
"PWM11"
$PN"12"55;
"CS1"
$PN"37"54;
"RGND1"
$PN"39"53;
"VSEN1"
$PN"40"25;
"VDDIO"
$PN"19"52;
"TEMP0"
$PN"44"51;
"VINSEN"
$PN"46"50;
"VMON||IINSEN"
$PN"45"49;
"VCCS"
$PN"48"27;
"PWM6"
$PN"7"48;
"PG0"
$PN"16"47;
"PWM1"
$PN"2"46;
"VSEN0"
$PN"25"45;
"PWM5"
$PN"6"26;
"PWM4"
$PN"5"44;
"PMSDA"
$PN"13"43;
"RGND0"
$PN"26"23;
"EN0"
$PN"17"42;
"NPMALERT \B"
$PN"15"41;
"SVD"
$PN"21"40;
"PG1"
$PN"20"39;
"CS4"
$PN"34"38;
"CS5"
$PN"33"37;
"RESET_L \B"
$PN"18"36;
"SVTO"
$PN"23"35;
"CS6"
$PN"32"34;
"SVC"
$PN"22"33;
"PMSCL"
$PN"14"32;
"SVTI"
$PN"24"31;
"VCC"
$PN"47"30;
"CS11"
$PN"27"29;
%"MOSFET_PCH_GDS_ESD_PROTECTED"
"1","(-3325,3050)","6","pure_quanta","I13";
;
LOCATION"PQ12"
$SEC"1"
CDS_SEC"1"
VALUE"PJA3415AE"
MATERIAL"IC"
PART_TYPE"SMLF"
NEEDS_NO_SIZE"TRUE"
CDS_LIB"pure_quanta"
CDS_LMAN_SYM_OUTLINE"-125,150,125,-150"
PART_NUMBER"BAM34150008";
"S"
$PN"S"80;
"G"
$PN"G"96;
"D"
$PN"D"62;
%"Q_RES"
"2","(-4550,2325)","0","pure_quanta","I130";
;
LOCATION"R6088"
$SEC"1"
CDS_SEC"1"
VALUE"10K"
MATERIAL"EMPTY"
TOLERANCE"1%"
WATTAGE"1/16W"
PACK_TYPE"0402LF"
CDS_LIB"pure_quanta"
PART_NUMBER"CS31002FB08";
"A"
$PN"1"93;
"B"
$PN"2"83;
%"Q_CAP"
"2","(-3600,7350)","0","pure_quanta","I131";
;
LOCATION"C5022"
$SEC"1"
CDS_SEC"1"
VOLTAGE"50V"
MATERIAL"X7R"
PACK_TYPE"0402"
VALUE"1000PF"
TOLERANCE"5%"
CDS_LIB"pure_quanta"
PART_NUMBER"TMP_QCH21006JB10";
"A"
$PN"1"5;
"B"
$PN"2"98;
%"UNIVERSAL_GND"
"1","(-3900,7350)","7","pure_quanta_power","I132";
;
CDS_LIB"pure_quanta_power"
HDL_POWER"GND";
"A"5;
%"Q_CAP"
"2","(-3450,5550)","0","pure_quanta","I133";
;
LOCATION"C5020"
$SEC"1"
CDS_SEC"1"
VALUE"1000PF"
PACK_TYPE"0402"
TOLERANCE"5%"
MATERIAL"X7R"
VOLTAGE"50V"
CDS_LIB"pure_quanta"
PART_NUMBER"TMP_QCH21006JB10";
"A"
$PN"1"6;
"B"
$PN"2"90;
%"UNIVERSAL_GND"
"1","(-3750,5550)","7","pure_quanta_power","I134";
;
CDS_LIB"pure_quanta_power"
HDL_POWER"GND";
"A"6;
%"UNIVERSAL_GND"
"1","(-3925,2100)","7","pure_quanta_power","I135";
;
CDS_LIB"pure_quanta_power"
HDL_POWER"GND";
"A"7;
%"Q_CAP"
"2","(-3625,2100)","0","pure_quanta","I136";
;
LOCATION"C5006"
$SEC"1"
CDS_SEC"1"
VOLTAGE"50V"
MATERIAL"X7R"
PACK_TYPE"0402"
VALUE"1000PF"
TOLERANCE"5%"
CDS_LIB"pure_quanta"
PART_NUMBER"TMP_QCH21006JB10";
"A"
$PN"1"7;
"B"
$PN"2"92;
%"Q_RES"
"1","(-2875,6775)","0","pure_quanta","I137";
;
LOCATION"PR8011"
$SEC"1"
CDS_SEC"1"
VALUE"0"
TOLERANCE"5%"
PACK_TYPE"0402LF"
MATERIAL"CHIP"
WATTAGE"1/16W"
CDS_LIB"pure_quanta"
PART_NUMBER"CS00002JB13";
"B"
$PN"2"33;
"A"
$PN"1"76;
%"Q_RES"
"1","(-2875,6625)","0","pure_quanta","I138";
;
LOCATION"PR8012"
$SEC"1"
CDS_SEC"1"
WATTAGE"1/16W"
MATERIAL"CHIP"
VALUE"0"
TOLERANCE"5%"
PACK_TYPE"0402LF"
CDS_LIB"pure_quanta"
PART_NUMBER"CS00002JB13";
"B"
$PN"2"40;
"A"
$PN"1"75;
%"Q_RES"
"2","(-4000,3250)","0","pure_quanta","I17";
;
LOCATION"PR232"
$SEC"1"
CDS_SEC"1"
WATTAGE"1/16W"
MATERIAL"CHIP"
TOLERANCE"1%"
VALUE"1K"
PACK_TYPE"0402LF"
CDS_LIB"pure_quanta"
PART_NUMBER"CS21002FB06";
"A"
$PN"1"80;
"B"
$PN"2"96;
%"VCC_CORE"
"1","(-4000,3500)","0","pure_quanta_power","I18";
;
HDL_POWER"P3V3_AUX"
CDS_LIB"pure_quanta_power";
"A"80;
%"Q_RES"
"1","(-3425,3600)","0","pure_quanta","I19";
;
LOCATION"PR460"
$SEC"1"
CDS_SEC"1"
WATTAGE"1/16W"
MATERIAL"CHIP"
PACK_TYPE"0402LF"
TOLERANCE"1%"
VALUE"49.9"
CDS_LIB"pure_quanta"
PART_NUMBER"CS04992FB07";
"B"
$PN"2"13;
"A"
$PN"1"53;
%"Q_RES"
"1","(-4700,2575)","0","pure_quanta","I2";
;
LOCATION"R8224"
$SEC"1"
CDS_SEC"1"
TOLERANCE"5%"
PACK_TYPE"0402LF"
WATTAGE"1/16W"
MATERIAL"CHIP"
VALUE"0"
CDS_LIB"pure_quanta"
PART_NUMBER"CS00002JB13";
"B"
$PN"2"93;
"A"
$PN"1"97;
%"Q_RES"
"1","(-3400,4275)","0","pure_quanta","I22";
;
LOCATION"PR227"
$SEC"1"
CDS_SEC"1"
VALUE"49.9"
PACK_TYPE"0402LF"
TOLERANCE"1%"
MATERIAL"CHIP"
WATTAGE"1/16W"
CDS_LIB"pure_quanta"
PART_NUMBER"CS04992FB07";
"B"
$PN"2"87;
"A"
$PN"1"94;
%"Q_RES"
"1","(-3400,4700)","0","pure_quanta","I23";
;
LOCATION"PR226"
$SEC"1"
CDS_SEC"1"
WATTAGE"1/16W"
VALUE"49.9"
MATERIAL"CHIP"
TOLERANCE"1%"
PACK_TYPE"0402LF"
CDS_LIB"pure_quanta"
PART_NUMBER"CS04992FB07";
"B"
$PN"2"14;
"A"
$PN"1"23;
%"UNIVERSAL_GND"
"1","(-5000,5675)","0","pure_quanta_power","I28";
;
CDS_LIB"pure_quanta_power"
HDL_POWER"GND";
"A"81;
%"Q_RES"
"2","(-5000,6125)","0","pure_quanta","I29";
;
LOCATION"PR217"
$SEC"1"
CDS_SEC"1"
TOLERANCE"5%"
PACK_TYPE"0402LF"
MATERIAL"CHIP"
VALUE"0"
WATTAGE"1/16W"
CDS_LIB"pure_quanta"
PART_NUMBER"CS00002JB13";
"A"
$PN"1"78;
"B"
$PN"2"81;
%"Q_CAP"
"1","(-4325,2400)","0","pure_quanta","I3";
;
LOCATION"C8356"
$SEC"1"
CDS_SEC"1"
PACK_TYPE"0402"
TOLERANCE"5%"
VOLTAGE"50V"
MATERIAL"X7R"
VALUE"1000PF"
CDS_LIB"pure_quanta"
PART_NUMBER"TMP_QCH21006JB10";
"B"
$PN"2"83;
"A"
$PN"1"93;
%"Q_RES"
"2","(-4825,6125)","0","pure_quanta","I30";
;
LOCATION"R8219"
$SEC"1"
CDS_SEC"1"
PACK_TYPE"0402LF"
WATTAGE"1/16W"
MATERIAL"EMPTY"
VALUE"1K"
TOLERANCE"1%"
CDS_LIB"pure_quanta"
PART_NUMBER"CS21002FB06";
"A"
$PN"1"74;
"B"
$PN"2"81;
%"Q_CAP"
"1","(-4650,6100)","0","pure_quanta","I31";
;
LOCATION"C308"
$SEC"1"
CDS_SEC"1"
PACK_TYPE"0402"
TOLERANCE"5%"
MATERIAL"EMPTY"
VOLTAGE"50V"
VALUE"10PF"
CDS_LIB"pure_quanta"
PART_NUMBER"CH01006JB08";
"B"
$PN"2"81;
"A"
$PN"1"74;
%"Q_CAP"
"1","(-4450,6125)","0","pure_quanta","I32";
;
LOCATION"C309"
$SEC"1"
CDS_SEC"1"
VOLTAGE"50V"
PACK_TYPE"0402"
TOLERANCE"5%"
MATERIAL"EMPTY"
VALUE"10PF"
CDS_LIB"pure_quanta"
PART_NUMBER"CH01006JB08";
"B"
$PN"2"81;
"A"
$PN"1"75;
%"Q_CAP"
"1","(-4250,6125)","0","pure_quanta","I33";
;
LOCATION"C310"
$SEC"1"
CDS_SEC"1"
VOLTAGE"50V"
TOLERANCE"5%"
PACK_TYPE"0402"
VALUE"10PF"
MATERIAL"EMPTY"
CDS_LIB"pure_quanta"
PART_NUMBER"CH01006JB08";
"B"
$PN"2"81;
"A"
$PN"1"76;
%"Q_RES"
"1","(-3350,5375)","0","pure_quanta","I34";
;
LOCATION"PR228"
$SEC"1"
CDS_SEC"1"
PACK_TYPE"0402LF"
MATERIAL"CHIP"
VALUE"49.9"
TOLERANCE"1%"
WATTAGE"1/16W"
CDS_LIB"pure_quanta"
PART_NUMBER"CS04992FB07";
"B"
$PN"2"28;
"A"
$PN"1"24;
%"Q_RES"
"2","(-4950,7100)","0","pure_quanta","I38";
;
LOCATION"PR218"
$SEC"1"
CDS_SEC"1"
WATTAGE"1/16W"
VALUE"1K"
PACK_TYPE"0402LF"
MATERIAL"EMPTY"
TOLERANCE"1%"
CDS_LIB"pure_quanta"
PART_NUMBER"CS21002FB06";
"A"
$PN"1"82;
"B"
$PN"2"78;
%"VCC_CORE"
"1","(-4950,7450)","0","pure_quanta_power","I39";
;
HDL_POWER"PVDD18_S5_P1"
CDS_LIB"pure_quanta_power";
"A"82;
%"UNIVERSAL_GND"
"1","(-4325,2100)","0","pure_quanta_power","I4";
;
CDS_LIB"pure_quanta_power"
HDL_POWER"GND";
"A"83;
%"Q_RES"
"2","(-4575,7100)","0","pure_quanta","I40";
;
LOCATION"R8220"
$SEC"1"
CDS_SEC"1"
VALUE"1K"
WATTAGE"1/16W"
MATERIAL"EMPTY"
PACK_TYPE"0402LF"
TOLERANCE"1%"
CDS_LIB"pure_quanta"
PART_NUMBER"CS21002FB06";
"A"
$PN"1"82;
"B"
$PN"2"74;
%"Q_RES"
"2","(-4400,7100)","0","pure_quanta","I41";
;
LOCATION"R8222"
$SEC"1"
CDS_SEC"1"
MATERIAL"EMPTY"
WATTAGE"1/16W"
TOLERANCE"1%"
PACK_TYPE"0402LF"
VALUE"1K"
CDS_LIB"pure_quanta"
PART_NUMBER"CS21002FB06";
"A"
$PN"1"82;
"B"
$PN"2"75;
%"Q_RES"
"2","(-4200,7100)","0","pure_quanta","I42";
;
LOCATION"R8225"
$SEC"1"
CDS_SEC"1"
PACK_TYPE"0402LF"
TOLERANCE"1%"
MATERIAL"EMPTY"
VALUE"1K"
WATTAGE"1/16W"
CDS_LIB"pure_quanta"
PART_NUMBER"CS21002FB06";
"A"
$PN"1"82;
"B"
$PN"2"76;
%"VCC_CORE"
"1","(-3300,7475)","0","pure_quanta_power","I45";
;
HDL_POWER"P3V3_AUX"
CDS_LIB"pure_quanta_power";
"A"8;
%"UNIVERSAL_GND"
"1","(-2600,1400)","0","pure_quanta_power","I46";
;
CDS_LIB"pure_quanta_power"
HDL_POWER"GND";
"A"84;
%"Q_CAP"
"1","(-2600,1725)","0","pure_quanta","I47";
;
LOCATION"PC357"
$SEC"1"
CDS_SEC"1"
VALUE"0.1UF"
PACK_TYPE"0402"
MATERIAL"X7R"
TOLERANCE"10%"
VOLTAGE"25V"
CDS_LIB"pure_quanta"
PART_NUMBER"CH4104K1B00";
"B"
$PN"2"84;
"A"
$PN"1"49;
%"VCC_CORE"
"1","(-2325,1775)","0","pure_quanta_power","I48";
;
HDL_POWER"P12V_AUX"
CDS_LIB"pure_quanta_power";
"A"85;
%"Q_RES"
"1","(-2075,1700)","0","pure_quanta","I49";
;
LOCATION"PR251"
$SEC"1"
CDS_SEC"1"
WATTAGE"1/16W"
MATERIAL"CHIP"
PACK_TYPE"0402LF"
TOLERANCE"5%"
VALUE"0"
CDS_LIB"pure_quanta"
PART_NUMBER"CS00002JB13";
"B"
$PN"2"50;
"A"
$PN"1"85;
%"Q_RES"
"1","(-2775,1975)","0","pure_quanta","I50";
;
LOCATION"R8243"
$SEC"1"
CDS_SEC"1"
VALUE"33"
PACK_TYPE"0402LF"
TOLERANCE"5%"
WATTAGE"1/16W"
MATERIAL"CHIP"
CDS_LIB"pure_quanta"
PART_NUMBER"CS03302JB10";
"B"
$PN"2"39;
"A"
$PN"1"92;
%"Q_RES"
"1","(-2775,2125)","0","pure_quanta","I51";
;
LOCATION"R8242"
$SEC"1"
CDS_SEC"1"
VALUE"1K"
PACK_TYPE"0402LF"
TOLERANCE"1%"
MATERIAL"CHIP"
WATTAGE"1/16W"
CDS_LIB"pure_quanta"
PART_NUMBER"CS21002FB06";
"B"
$PN"2"39;
"A"
$PN"1"3;
%"Q_CAP"
"2","(-1975,2125)","0","pure_quanta","I52";
;
LOCATION"C8362"
$SEC"1"
CDS_SEC"1"
TOLERANCE"5%"
PACK_TYPE"0402"
VOLTAGE"50V"
MATERIAL"EMPTY"
VALUE"1000PF"
CDS_LIB"pure_quanta"
PART_NUMBER"TMP_QCH21006JB10";
"A"
$PN"1"39;
"B"
$PN"2"12;
%"VCC_CORE"
"1","(-2375,2925)","0","pure_quanta_power","I53";
;
HDL_POWER"PVDD18_S5_P1"
CDS_LIB"pure_quanta_power";
"A"52;
%"UNIVERSAL_GND"
"1","(-1800,1300)","0","pure_quanta_power","I54";
;
CDS_LIB"pure_quanta_power"
HDL_POWER"GND";
"A"9;
%"Q_RES"
"2","(-1800,1500)","0","pure_quanta","I55";
;
LOCATION"PR603"
$SEC"1"
CDS_SEC"1"
WATTAGE"1/16W"
MATERIAL"EMPTY"
TOLERANCE"1%"
VALUE"4.99K"
PACK_TYPE"0402LF"
CDS_LIB"pure_quanta"
PART_NUMBER"CS24992FB07";
"A"
$PN"1"50;
"B"
$PN"2"9;
%"Q_CAP"
"1","(-1450,1525)","0","pure_quanta","I56";
;
LOCATION"PC364"
$SEC"1"
CDS_SEC"1"
PACK_TYPE"0402"
VOLTAGE"25V"
VALUE"0.1UF"
TOLERANCE"10%"
MATERIAL"X7R"
CDS_LIB"pure_quanta"
PART_NUMBER"CH4104K1B00";
"B"
$PN"2"10;
"A"
$PN"1"50;
%"UNIVERSAL_GND"
"1","(-1450,1300)","0","pure_quanta_power","I57";
;
CDS_LIB"pure_quanta_power"
HDL_POWER"GND";
"A"10;
%"UNIVERSAL_GND"
"1","(-1250,1550)","0","pure_quanta_power","I58";
;
CDS_LIB"pure_quanta_power"
HDL_POWER"GND";
"A"61;
%"UNIVERSAL_GND"
"1","(-1425,2850)","1","pure_quanta_power","I59";
;
CDS_LIB"pure_quanta_power"
HDL_POWER"GND";
"A"11;
%"MOSFET_N"
"1","(-4050,2675)","0","pure_quanta","I6";
;
LOCATION"PQ16"
$SEC"1"
CDS_SEC"1"
VALUE"BSS138K"
MATERIAL"IC"
PACK_TYPE"SMLF"
MANUF_PN"BSS138K"
CDS_LMAN_SYM_OUTLINE"-50,50,100,-150"
CDS_LIB"pure_quanta"
PART_NUMBER"BAM138K0000";
"GATE"
$PN"G"93;
"SOURCE"
$PN"S"88;
"DRAIN"
$PN"D"96;
%"Q_CAP"
"2","(-1825,2850)","0","pure_quanta","I60";
;
LOCATION"PC363"
$SEC"1"
CDS_SEC"1"
TOLERANCE"10%"
PACK_TYPE"0402"
MATERIAL"X7R"
VALUE"1UF"
VOLTAGE"6.3V"
CDS_LIB"pure_quanta"
PART_NUMBER"CH5101K1B01";
"A"
$PN"1"52;
"B"
$PN"2"11;
%"UNIVERSAL_GND"
"1","(-1275,2125)","1","pure_quanta_power","I61";
;
CDS_LIB"pure_quanta_power"
HDL_POWER"GND";
"A"12;
%"UNIVERSAL_GND"
"1","(-2900,3500)","0","pure_quanta_power","I62";
;
CDS_LIB"pure_quanta_power"
HDL_POWER"GND";
"A"13;
%"VCC_CORE"
"1","(-2675,3650)","0","pure_quanta_power","I63";
;
HDL_POWER"PVDD18_S5_P1"
CDS_LIB"pure_quanta_power";
"A"86;
%"Q_RES"
"1","(-2200,3225)","0","pure_quanta","I64";
;
LOCATION"R8241"
$SEC"1"
CDS_SEC"1"
VALUE"0"
WATTAGE"1/16W"
MATERIAL"CHIP"
TOLERANCE"5%"
PACK_TYPE"0402LF"
CDS_LIB"pure_quanta"
PART_NUMBER"CS00002JB13";
"B"
$PN"2"60;
"A"
$PN"1"95;
%"Q_RES"
"1","(-2200,3375)","0","pure_quanta","I65";
;
LOCATION"R240"
$SEC"1"
CDS_SEC"1"
VALUE"100"
TOLERANCE"1%"
PACK_TYPE"0402LF"
WATTAGE"1/16W"
MATERIAL"CHIP"
CDS_LIB"pure_quanta"
PART_NUMBER"CS11002FB07";
"B"
$PN"2"36;
"A"
$PN"1"89;
%"Q_RES"
"1","(-2225,3525)","0","pure_quanta","I66";
;
LOCATION"R8247"
$SEC"1"
CDS_SEC"1"
TOLERANCE"1%"
VALUE"1K"
MATERIAL"CHIP"
PACK_TYPE"0402LF"
WATTAGE"1/16W"
CDS_LIB"pure_quanta"
PART_NUMBER"CS21002FB06";
"B"
$PN"2"36;
"A"
$PN"1"86;
%"Q_CAP"
"1","(-2025,3950)","0","pure_quanta","I67";
;
LOCATION"PC361"
$SEC"1"
CDS_SEC"1"
VOLTAGE"50V"
VALUE"3300PF"
PACK_TYPE"0402"
TOLERANCE"10%"
MATERIAL"X7R"
CDS_LIB"pure_quanta"
PART_NUMBER"TMP_QCH2336K1B12";
"B"
$PN"2"53;
"A"
$PN"1"25;
%"VCC_CORE"
"1","(-2875,4425)","0","pure_quanta_power","I68";
;
HDL_POWER"PVDDIO_P1"
CDS_LIB"pure_quanta_power";
"A"87;
%"Q_RES"
"1","(-2475,4125)","0","pure_quanta","I69";
;
LOCATION"PR246"
$SEC"1"
CDS_SEC"1"
PACK_TYPE"0402LF"
MATERIAL"CHIP"
WATTAGE"1/16W"
TOLERANCE"5%"
VALUE"0"
CDS_LIB"pure_quanta"
PART_NUMBER"CS00002JB13";
"B"
$PN"2"25;
"A"
$PN"1"94;
%"UNIVERSAL_GND"
"1","(-4000,2275)","0","pure_quanta_power","I7";
;
CDS_LIB"pure_quanta_power"
HDL_POWER"GND";
"A"88;
%"UNIVERSAL_GND"
"1","(-2875,4600)","0","pure_quanta_power","I70";
;
CDS_LIB"pure_quanta_power"
HDL_POWER"GND";
"A"14;
%"Q_RES"
"1","(-1550,3100)","0","pure_quanta","I71";
;
LOCATION"R8252"
$SEC"1"
CDS_SEC"1"
WATTAGE"1/16W"
VALUE"1K"
MATERIAL"CHIP"
TOLERANCE"1%"
PACK_TYPE"0402LF"
CDS_LIB"pure_quanta"
PART_NUMBER"CS21002FB06";
"B"
$PN"2"60;
"A"
$PN"1"52;
%"UNIVERSAL_GND"
"1","(850,1600)","0","pure_quanta_power","I72";
;
CDS_LIB"pure_quanta_power"
HDL_POWER"GND";
"A"15;
%"Q_CAP"
"1","(850,1850)","0","pure_quanta","I73";
;
LOCATION"PC368"
$SEC"1"
CDS_SEC"1"
PACK_TYPE"0402"
VALUE"470PF"
TOLERANCE"10%"
MATERIAL"X7R"
VOLTAGE"50V"
CDS_LIB"pure_quanta"
PART_NUMBER"TMP_QCH14706KB18";
"B"
$PN"2"15;
"A"
$PN"1"51;
%"UNIVERSAL_GND"
"1","(850,2175)","0","pure_quanta_power","I74";
;
CDS_LIB"pure_quanta_power"
HDL_POWER"GND";
"A"16;
%"Q_CAP"
"1","(850,2425)","0","pure_quanta","I75";
;
LOCATION"PC367"
$SEC"1"
CDS_SEC"1"
PACK_TYPE"0402"
VOLTAGE"50V"
VALUE"470PF"
TOLERANCE"10%"
MATERIAL"X7R"
CDS_LIB"pure_quanta"
PART_NUMBER"TMP_QCH14706KB18";
"B"
$PN"2"16;
"A"
$PN"1"63;
%"Q_RES"
"1","(925,4325)","0","pure_quanta","I76";
;
LOCATION"PR533"
$SEC"1"
CDS_SEC"1"
PACK_TYPE"0402LF"
TOLERANCE"5%"
MATERIAL"CHIP"
VALUE"0"
WATTAGE"1/16W"
CDS_LIB"pure_quanta"
PART_NUMBER"CS00002JB13";
"B"
$PN"2"2;
"A"
$PN"1"37;
%"Q_RES"
"1","(-2525,5225)","0","pure_quanta","I77";
;
LOCATION"PR245"
$SEC"1"
CDS_SEC"1"
PACK_TYPE"0402LF"
MATERIAL"CHIP"
TOLERANCE"5%"
VALUE"0"
WATTAGE"1/16W"
CDS_LIB"pure_quanta"
PART_NUMBER"CS00002JB13";
"B"
$PN"2"45;
"A"
$PN"1"24;
%"VCC_CORE"
"1","(-2675,5525)","0","pure_quanta_power","I78";
;
HDL_POWER"PVDDCR_CPU1_P1"
CDS_LIB"pure_quanta_power";
"A"28;
%"Q_CAP"
"1","(-2075,5050)","0","pure_quanta","I79";
;
LOCATION"PC358"
$SEC"1"
CDS_SEC"1"
PACK_TYPE"0402"
TOLERANCE"10%"
VOLTAGE"50V"
MATERIAL"X7R"
VALUE"3300PF"
CDS_LIB"pure_quanta"
PART_NUMBER"TMP_QCH2336K1B12";
"B"
$PN"2"23;
"A"
$PN"1"45;
%"Q_RES"
"2","(-3050,1700)","0","pure_quanta","I8";
;
LOCATION"PR231"
$SEC"1"
CDS_SEC"1"
VALUE"10K"
PACK_TYPE"0402LF"
TOLERANCE"1%"
WATTAGE"1/16W"
MATERIAL"CHIP"
CDS_LIB"pure_quanta"
PART_NUMBER"CS31002FB08";
"A"
$PN"1"49;
"B"
$PN"2"84;
%"Q_RES"
"1","(-2175,5775)","0","pure_quanta","I80";
;
LOCATION"R8250"
$SEC"1"
CDS_SEC"1"
MATERIAL"CHIP"
PACK_TYPE"0402LF"
TOLERANCE"5%"
WATTAGE"1/16W"
VALUE"33"
CDS_LIB"pure_quanta"
PART_NUMBER"CS03302JB10";
"B"
$PN"2"41;
"A"
$PN"1"90;
%"Q_RES"
"1","(-2175,5925)","0","pure_quanta","I81";
;
LOCATION"R8249"
$SEC"1"
CDS_SEC"1"
MATERIAL"CHIP"
PACK_TYPE"0402LF"
TOLERANCE"5%"
VALUE"0"
WATTAGE"1/16W"
CDS_LIB"pure_quanta"
PART_NUMBER"CS00002JB13";
"B"
$PN"2"43;
"A"
$PN"1"91;
%"Q_RES"
"1","(-2875,6475)","0","pure_quanta","I82";
;
LOCATION"R8238"
$SEC"1"
CDS_SEC"1"
PACK_TYPE"0402LF"
MATERIAL"CHIP"
WATTAGE"1/16W"
VALUE"49.9"
TOLERANCE"1%"
CDS_LIB"pure_quanta"
PART_NUMBER"CS04992FB07";
"B"
$PN"2"35;
"A"
$PN"1"74;
%"Q_RES"
"1","(-2875,6325)","0","pure_quanta","I83";
;
LOCATION"PR239"
$SEC"1"
CDS_SEC"1"
MATERIAL"CHIP"
VALUE"0"
WATTAGE"1/16W"
TOLERANCE"5%"
PACK_TYPE"0402LF"
CDS_LIB"pure_quanta"
PART_NUMBER"CS00002JB13";
"B"
$PN"2"31;
"A"
$PN"1"78;
%"Q_RES"
"1","(-2175,6075)","0","pure_quanta","I84";
;
LOCATION"R8248"
$SEC"1"
CDS_SEC"1"
MATERIAL"CHIP"
TOLERANCE"5%"
VALUE"0"
PACK_TYPE"0402LF"
WATTAGE"1/16W"
CDS_LIB"pure_quanta"
PART_NUMBER"CS00002JB13";
"B"
$PN"2"32;
"A"
$PN"1"77;
%"Q_CAP"
"2","(-2050,6950)","0","pure_quanta","I85";
;
LOCATION"C8359"
$SEC"1"
CDS_SEC"1"
TOLERANCE"5%"
VOLTAGE"50V"
PACK_TYPE"0402"
MATERIAL"X7R"
VALUE"1000PF"
CDS_LIB"pure_quanta"
PART_NUMBER"TMP_QCH21006JB10";
"A"
$PN"1"42;
"B"
$PN"2"17;
%"UNIVERSAL_GND"
"1","(-1325,6950)","1","pure_quanta_power","I86";
;
CDS_LIB"pure_quanta_power"
HDL_POWER"GND";
"A"17;
%"Q_RES"
"1","(-2875,7075)","0","pure_quanta","I87";
;
LOCATION"R8235"
$SEC"1"
CDS_SEC"1"
WATTAGE"1/16W"
TOLERANCE"5%"
VALUE"0"
PACK_TYPE"0402LF"
MATERIAL"CHIP"
CDS_LIB"pure_quanta"
PART_NUMBER"CS00002JB13";
"B"
$PN"2"42;
"A"
$PN"1"99;
%"Q_RES"
"1","(-2875,7225)","0","pure_quanta","I88";
;
LOCATION"R8234"
$SEC"1"
CDS_SEC"1"
MATERIAL"CHIP"
PACK_TYPE"0402LF"
VALUE"33"
WATTAGE"1/16W"
TOLERANCE"5%"
CDS_LIB"pure_quanta"
PART_NUMBER"CS03302JB10";
"B"
$PN"2"47;
"A"
$PN"1"98;
%"Q_RES"
"1","(-2875,7375)","0","pure_quanta","I89";
;
LOCATION"R8233"
$SEC"1"
CDS_SEC"1"
TOLERANCE"1%"
MATERIAL"CHIP"
VALUE"1K"
WATTAGE"1/16W"
PACK_TYPE"0402LF"
CDS_LIB"pure_quanta"
PART_NUMBER"CS21002FB06";
"B"
$PN"2"47;
"A"
$PN"1"8;
%"Q_RES"
"1","(-3400,1875)","0","pure_quanta","I9";
;
LOCATION"PR230"
$SEC"1"
CDS_SEC"1"
VALUE"40.2K"
TOLERANCE"1%"
MATERIAL"CHIP"
PACK_TYPE"0402LF"
CDS_LIB"pure_quanta"
WATTAGE"1/16W"
PART_NUMBER"CS34022FB04";
"B"
$PN"2"49;
"A"
$PN"1"1;
%"Q_CAP"
"2","(-2025,7375)","0","pure_quanta","I90";
;
LOCATION"C8360"
$SEC"1"
CDS_SEC"1"
TOLERANCE"5%"
PACK_TYPE"0402"
VOLTAGE"50V"
VALUE"1000PF"
MATERIAL"EMPTY"
CDS_LIB"pure_quanta"
PART_NUMBER"TMP_QCH21006JB10";
"A"
$PN"1"47;
"B"
$PN"2"18;
%"UNIVERSAL_GND"
"1","(-1325,7375)","1","pure_quanta_power","I91";
;
CDS_LIB"pure_quanta_power"
HDL_POWER"GND";
"A"18;
%"UNIVERSAL_GND"
"1","(475,6375)","0","pure_quanta_power","I92";
;
CDS_LIB"pure_quanta_power"
HDL_POWER"GND";
"A"19;
%"Q_CAP"
"1","(475,6600)","0","pure_quanta","I93";
;
LOCATION"PC93"
$SEC"1"
CDS_SEC"1"
PACK_TYPE"0402"
VOLTAGE"25V"
VALUE"0.1UF"
TOLERANCE"10%"
MATERIAL"X7R"
CDS_LIB"pure_quanta"
PART_NUMBER"CH4104K1B00";
"B"
$PN"2"19;
"A"
$PN"1"27;
%"UNIVERSAL_GND"
"1","(475,6850)","0","pure_quanta_power","I94";
;
CDS_LIB"pure_quanta_power"
HDL_POWER"GND";
"A"20;
%"Q_CAP"
"1","(475,7075)","0","pure_quanta","I95";
;
LOCATION"PC29"
$SEC"1"
CDS_SEC"1"
PACK_TYPE"0402"
MATERIAL"X7R"
VOLTAGE"25V"
VALUE"0.1UF"
TOLERANCE"10%"
CDS_LIB"pure_quanta"
PART_NUMBER"CH4104K1B00";
"B"
$PN"2"20;
"A"
$PN"1"30;
%"UNIVERSAL_GND"
"1","(850,6375)","0","pure_quanta_power","I96";
;
CDS_LIB"pure_quanta_power"
HDL_POWER"GND";
"A"21;
%"Q_CAP"
"1","(850,6575)","0","pure_quanta","I97";
;
LOCATION"PC366"
$SEC"1"
CDS_SEC"1"
VALUE"10UF"
VOLTAGE"6.3V"
TOLERANCE"20%"
MATERIAL"X6S"
PACK_TYPE"C0402"
CDS_LIB"pure_quanta"
PART_NUMBER"CH6101MEB03";
"B"
$PN"2"21;
"A"
$PN"1"27;
%"UNIVERSAL_GND"
"1","(850,6850)","0","pure_quanta_power","I98";
;
CDS_LIB"pure_quanta_power"
HDL_POWER"GND";
"A"22;
%"Q_CAP"
"1","(850,7050)","0","pure_quanta","I99";
;
LOCATION"PC365"
$SEC"1"
CDS_SEC"1"
VALUE"1UF"
PACK_TYPE"C0402"
VOLTAGE"16V"
TOLERANCE"10%"
MATERIAL"X6S"
CDS_LIB"pure_quanta"
PART_NUMBER"CH5103KEB01";
"B"
$PN"2"22;
"A"
$PN"1"30;
END.
